(kicad_pcb
	(version 20260206)
	(generator "pcbnew")
	(generator_version "10.0")
	(general
		(thickness 1.6)
		(legacy_teardrops no)
	)
	(paper "A4")
	(title_block
		(title "01162023_DA0F0TEBIF0_F0T_Expander_BD_F_brd_V02_OCP.brd")
		(comment 1 "Grand Teton / footprints 5502-5508 of 9728")
	)
	(layers
		(0 "F.Cu" signal "TOP")
		(4 "In1.Cu" signal "GND")
		(6 "In2.Cu" signal "VCC")
		(8 "In3.Cu" signal "VCC1")
		(10 "In4.Cu" signal "GND1")
		(12 "In5.Cu" signal "IN1")
		(14 "In6.Cu" signal "GND2")
		(16 "In7.Cu" signal "IN2")
		(18 "In8.Cu" signal "GND3")
		(20 "In9.Cu" signal "IN3")
		(22 "In10.Cu" signal "GND4")
		(24 "In11.Cu" signal "IN4")
		(26 "In12.Cu" signal "GND5")
		(28 "In13.Cu" signal "IN5")
		(30 "In14.Cu" signal "GND6")
		(32 "In15.Cu" signal "IN6")
		(34 "In16.Cu" signal "GND7")
		(2 "B.Cu" signal "BOTTOM")
		(9 "F.Adhes" user "F.Adhesive")
		(11 "B.Adhes" user "B.Adhesive")
		(13 "F.Paste" user "Package Geometry/Pastemask Top")
		(15 "B.Paste" user "Package Geometry/Pastemask Bottom")
		(5 "F.SilkS" user "Ref Des/Silkscreen Top")
		(7 "B.SilkS" user "Ref Des/Silkscreen Bottom")
		(1 "F.Mask" user "Board Geometry/Soldermask Top")
		(3 "B.Mask" user "Board Geometry/Soldermask Bottom")
		(17 "Dwgs.User" user "User.Drawings")
		(19 "Cmts.User" user "User.Comments")
		(21 "Eco1.User" user "User.Eco1")
		(23 "Eco2.User" user "User.Eco2")
		(25 "Edge.Cuts" user "Board Geometry/Outline")
		(27 "Margin" user)
		(31 "F.CrtYd" user "Package Geometry/Place Bound Top")
		(29 "B.CrtYd" user "Package Geometry/Place Bound Bottom")
		(35 "F.Fab" user "Ref Des/Assembly Top")
		(33 "B.Fab" user "Ref Des/Assembly Bottom")
	)
	(footprint ""
		(layer "F.Cu")
		(at 295.877742 -116.550186 180)
		(property "Reference" "R262"
			(at 0 0 180)
			(layer "F.SilkS")
			(hide yes)
			(effects
				(font
					(size 1.27 1.27)
				)
			)
		)
		(property "Value" ""
			(at 0 0 180)
			(layer "F.Fab")
			(effects
				(font
					(size 1.27 1.27)
				)
			)
		)
		(duplicate_pad_numbers_are_jumpers no)
		(fp_line
			(start 0.7874 0.4064)
			(end -0.7874 0.4064)
			(stroke
				(width 0.1524)
				(type default)
			)
			(layer "F.SilkS")
		)
		(fp_line
			(start 0.7874 -0.4064)
			(end 0.7874 0.4064)
			(stroke
				(width 0.1524)
				(type default)
			)
			(layer "F.SilkS")
		)
		(fp_line
			(start -0.7874 0.4064)
			(end -0.7874 -0.4064)
			(stroke
				(width 0.1524)
				(type default)
			)
			(layer "F.SilkS")
		)
		(fp_line
			(start -0.7874 -0.4064)
			(end 0.7874 -0.4064)
			(stroke
				(width 0.1524)
				(type default)
			)
			(layer "F.SilkS")
		)
		(fp_line
			(start 0.67945 0.3048)
			(end 0.120396 0.3048)
			(stroke
				(width 0.1)
				(type default)
			)
			(layer "F.Fab")
		)
		(fp_line
			(start 0.67945 -0.3048)
			(end 0.67945 0.3048)
			(stroke
				(width 0.1)
				(type default)
			)
			(layer "F.Fab")
		)
		(fp_line
			(start 0.12065 -0.2794)
			(end 0.12065 -0.3048)
			(stroke
				(width 0.1)
				(type default)
			)
			(layer "F.Fab")
		)
		(fp_line
			(start 0.12065 -0.3048)
			(end 0.67945 -0.3048)
			(stroke
				(width 0.1)
				(type default)
			)
			(layer "F.Fab")
		)
		(fp_line
			(start 0.120396 0.3048)
			(end 0.120396 0.2794)
			(stroke
				(width 0.1)
				(type default)
			)
			(layer "F.Fab")
		)
		(fp_line
			(start 0.120396 0.2794)
			(end -0.12065 0.2794)
			(stroke
				(width 0.1)
				(type default)
			)
			(layer "F.Fab")
		)
		(fp_line
			(start -0.12065 0.3048)
			(end -0.67945 0.3048)
			(stroke
				(width 0.1)
				(type default)
			)
			(layer "F.Fab")
		)
		(fp_line
			(start -0.12065 0.2794)
			(end -0.12065 0.3048)
			(stroke
				(width 0.1)
				(type default)
			)
			(layer "F.Fab")
		)
		(fp_line
			(start -0.12065 -0.2794)
			(end 0.12065 -0.2794)
			(stroke
				(width 0.1)
				(type default)
			)
			(layer "F.Fab")
		)
		(fp_line
			(start -0.12065 -0.305054)
			(end -0.12065 -0.2794)
			(stroke
				(width 0.1)
				(type default)
			)
			(layer "F.Fab")
		)
		(fp_line
			(start -0.67945 0.3048)
			(end -0.67945 -0.305054)
			(stroke
				(width 0.1)
				(type default)
			)
			(layer "F.Fab")
		)
		(fp_line
			(start -0.67945 -0.305054)
			(end -0.12065 -0.305054)
			(stroke
				(width 0.1)
				(type default)
			)
			(layer "F.Fab")
		)
		(pad "1" smd circle
			(at -0.40005 0 180)
			(size 0 0)
			(layers "F.Cu" "F.Mask" "F.Paste")
			(net "PRSNTB2_NIC5_N")
		)
		(pad "2" smd circle
			(at 0.40005 0 180)
			(size 0 0)
			(layers "F.Cu" "F.Mask" "F.Paste")
			(net "P3V3_AUX")
		)
	)
	(footprint ""
		(layer "F.Cu")
		(at 173.966886 -52.543456 180)
		(property "Reference" "PC526"
			(at 0 0 180)
			(layer "F.SilkS")
			(hide yes)
			(effects
				(font
					(size 1.27 1.27)
				)
			)
		)
		(property "Value" ""
			(at 0 0 180)
			(layer "F.Fab")
			(effects
				(font
					(size 1.27 1.27)
				)
			)
		)
		(duplicate_pad_numbers_are_jumpers no)
		(fp_line
			(start 0.7874 0.4064)
			(end -0.7874 0.4064)
			(stroke
				(width 0.1524)
				(type default)
			)
			(layer "F.SilkS")
		)
		(fp_line
			(start 0.7874 -0.4064)
			(end 0.7874 0.4064)
			(stroke
				(width 0.1524)
				(type default)
			)
			(layer "F.SilkS")
		)
		(fp_line
			(start -0.7874 0.4064)
			(end -0.7874 -0.4064)
			(stroke
				(width 0.1524)
				(type default)
			)
			(layer "F.SilkS")
		)
		(fp_line
			(start -0.7874 -0.4064)
			(end 0.7874 -0.4064)
			(stroke
				(width 0.1524)
				(type default)
			)
			(layer "F.SilkS")
		)
		(fp_line
			(start 0.67945 0.3048)
			(end 0.120396 0.3048)
			(stroke
				(width 0.1)
				(type default)
			)
			(layer "F.Fab")
		)
		(fp_line
			(start 0.67945 -0.3048)
			(end 0.67945 0.3048)
			(stroke
				(width 0.1)
				(type default)
			)
			(layer "F.Fab")
		)
		(fp_line
			(start 0.12065 -0.2794)
			(end 0.12065 -0.3048)
			(stroke
				(width 0.1)
				(type default)
			)
			(layer "F.Fab")
		)
		(fp_line
			(start 0.12065 -0.3048)
			(end 0.67945 -0.3048)
			(stroke
				(width 0.1)
				(type default)
			)
			(layer "F.Fab")
		)
		(fp_line
			(start 0.120396 0.3048)
			(end 0.120396 0.2794)
			(stroke
				(width 0.1)
				(type default)
			)
			(layer "F.Fab")
		)
		(fp_line
			(start 0.120396 0.2794)
			(end -0.12065 0.2794)
			(stroke
				(width 0.1)
				(type default)
			)
			(layer "F.Fab")
		)
		(fp_line
			(start -0.12065 0.3048)
			(end -0.67945 0.3048)
			(stroke
				(width 0.1)
				(type default)
			)
			(layer "F.Fab")
		)
		(fp_line
			(start -0.12065 0.2794)
			(end -0.12065 0.3048)
			(stroke
				(width 0.1)
				(type default)
			)
			(layer "F.Fab")
		)
		(fp_line
			(start -0.12065 -0.2794)
			(end 0.12065 -0.2794)
			(stroke
				(width 0.1)
				(type default)
			)
			(layer "F.Fab")
		)
		(fp_line
			(start -0.12065 -0.305054)
			(end -0.12065 -0.2794)
			(stroke
				(width 0.1)
				(type default)
			)
			(layer "F.Fab")
		)
		(fp_line
			(start -0.67945 0.3048)
			(end -0.67945 -0.305054)
			(stroke
				(width 0.1)
				(type default)
			)
			(layer "F.Fab")
		)
		(fp_line
			(start -0.67945 -0.305054)
			(end -0.12065 -0.305054)
			(stroke
				(width 0.1)
				(type default)
			)
			(layer "F.Fab")
		)
		(pad "1" smd circle
			(at -0.40005 0 180)
			(size 0 0)
			(layers "F.Cu" "F.Mask" "F.Paste")
			(net "P3V3_SSD6")
		)
		(pad "2" smd circle
			(at 0.40005 0 180)
			(size 0 0)
			(layers "F.Cu" "F.Mask" "F.Paste")
			(net "GND")
		)
	)
	(footprint ""
		(layer "F.Cu")
		(at 104.609138 -109.432598 -90)
		(property "Reference" "PC607"
			(at 0 0 270)
			(layer "F.SilkS")
			(hide yes)
			(effects
				(font
					(size 1.27 1.27)
				)
			)
		)
		(property "Value" ""
			(at 0 0 270)
			(layer "F.Fab")
			(effects
				(font
					(size 1.27 1.27)
				)
			)
		)
		(duplicate_pad_numbers_are_jumpers no)
		(fp_line
			(start -0.7874 0.4064)
			(end -0.7874 -0.4064)
			(stroke
				(width 0.1524)
				(type default)
			)
			(layer "F.SilkS")
		)
		(fp_line
			(start 0.7874 0.4064)
			(end -0.7874 0.4064)
			(stroke
				(width 0.1524)
				(type default)
			)
			(layer "F.SilkS")
		)
		(fp_line
			(start -0.7874 -0.4064)
			(end 0.7874 -0.4064)
			(stroke
				(width 0.1524)
				(type default)
			)
			(layer "F.SilkS")
		)
		(fp_line
			(start 0.7874 -0.4064)
			(end 0.7874 0.4064)
			(stroke
				(width 0.1524)
				(type default)
			)
			(layer "F.SilkS")
		)
		(fp_line
			(start -0.67945 0.3048)
			(end -0.67945 -0.305054)
			(stroke
				(width 0.1)
				(type default)
			)
			(layer "F.Fab")
		)
		(fp_line
			(start -0.12065 0.3048)
			(end -0.67945 0.3048)
			(stroke
				(width 0.1)
				(type default)
			)
			(layer "F.Fab")
		)
		(fp_line
			(start 0.120396 0.3048)
			(end 0.120396 0.2794)
			(stroke
				(width 0.1)
				(type default)
			)
			(layer "F.Fab")
		)
		(fp_line
			(start 0.67945 0.3048)
			(end 0.120396 0.3048)
			(stroke
				(width 0.1)
				(type default)
			)
			(layer "F.Fab")
		)
		(fp_line
			(start -0.12065 0.2794)
			(end -0.12065 0.3048)
			(stroke
				(width 0.1)
				(type default)
			)
			(layer "F.Fab")
		)
		(fp_line
			(start 0.120396 0.2794)
			(end -0.12065 0.2794)
			(stroke
				(width 0.1)
				(type default)
			)
			(layer "F.Fab")
		)
		(fp_line
			(start -0.12065 -0.2794)
			(end 0.12065 -0.2794)
			(stroke
				(width 0.1)
				(type default)
			)
			(layer "F.Fab")
		)
		(fp_line
			(start 0.12065 -0.2794)
			(end 0.12065 -0.3048)
			(stroke
				(width 0.1)
				(type default)
			)
			(layer "F.Fab")
		)
		(fp_line
			(start 0.12065 -0.3048)
			(end 0.67945 -0.3048)
			(stroke
				(width 0.1)
				(type default)
			)
			(layer "F.Fab")
		)
		(fp_line
			(start 0.67945 -0.3048)
			(end 0.67945 0.3048)
			(stroke
				(width 0.1)
				(type default)
			)
			(layer "F.Fab")
		)
		(fp_line
			(start -0.67945 -0.305054)
			(end -0.12065 -0.305054)
			(stroke
				(width 0.1)
				(type default)
			)
			(layer "F.Fab")
		)
		(fp_line
			(start -0.12065 -0.305054)
			(end -0.12065 -0.2794)
			(stroke
				(width 0.1)
				(type default)
			)
			(layer "F.Fab")
		)
		(pad "1" smd circle
			(at -0.40005 0 270)
			(size 0 0)
			(layers "F.Cu" "F.Mask" "F.Paste")
			(net "P12V_NIC1_R")
		)
		(pad "2" smd circle
			(at 0.40005 0 270)
			(size 0 0)
			(layers "F.Cu" "F.Mask" "F.Paste")
			(net "GND")
		)
	)
	(footprint ""
		(layer "F.Cu")
		(at 32.411416 -283.643832 -90)
		(property "Reference" "R4565"
			(at 0 0 270)
			(layer "F.SilkS")
			(hide yes)
			(effects
				(font
					(size 1.27 1.27)
				)
			)
		)
		(property "Value" ""
			(at 0 0 270)
			(layer "F.Fab")
			(effects
				(font
					(size 1.27 1.27)
				)
			)
		)
		(duplicate_pad_numbers_are_jumpers no)
		(fp_line
			(start -0.7874 0.4064)
			(end -0.7874 -0.4064)
			(stroke
				(width 0.1524)
				(type default)
			)
			(layer "F.SilkS")
		)
		(fp_line
			(start 0.7874 0.4064)
			(end -0.7874 0.4064)
			(stroke
				(width 0.1524)
				(type default)
			)
			(layer "F.SilkS")
		)
		(fp_line
			(start -0.7874 -0.4064)
			(end 0.7874 -0.4064)
			(stroke
				(width 0.1524)
				(type default)
			)
			(layer "F.SilkS")
		)
		(fp_line
			(start 0.7874 -0.4064)
			(end 0.7874 0.4064)
			(stroke
				(width 0.1524)
				(type default)
			)
			(layer "F.SilkS")
		)
		(fp_line
			(start -0.67945 0.3048)
			(end -0.67945 -0.305054)
			(stroke
				(width 0.1)
				(type default)
			)
			(layer "F.Fab")
		)
		(fp_line
			(start -0.12065 0.3048)
			(end -0.67945 0.3048)
			(stroke
				(width 0.1)
				(type default)
			)
			(layer "F.Fab")
		)
		(fp_line
			(start 0.120396 0.3048)
			(end 0.120396 0.2794)
			(stroke
				(width 0.1)
				(type default)
			)
			(layer "F.Fab")
		)
		(fp_line
			(start 0.67945 0.3048)
			(end 0.120396 0.3048)
			(stroke
				(width 0.1)
				(type default)
			)
			(layer "F.Fab")
		)
		(fp_line
			(start -0.12065 0.2794)
			(end -0.12065 0.3048)
			(stroke
				(width 0.1)
				(type default)
			)
			(layer "F.Fab")
		)
		(fp_line
			(start 0.120396 0.2794)
			(end -0.12065 0.2794)
			(stroke
				(width 0.1)
				(type default)
			)
			(layer "F.Fab")
		)
		(fp_line
			(start -0.12065 -0.2794)
			(end 0.12065 -0.2794)
			(stroke
				(width 0.1)
				(type default)
			)
			(layer "F.Fab")
		)
		(fp_line
			(start 0.12065 -0.2794)
			(end 0.12065 -0.3048)
			(stroke
				(width 0.1)
				(type default)
			)
			(layer "F.Fab")
		)
		(fp_line
			(start 0.12065 -0.3048)
			(end 0.67945 -0.3048)
			(stroke
				(width 0.1)
				(type default)
			)
			(layer "F.Fab")
		)
		(fp_line
			(start 0.67945 -0.3048)
			(end 0.67945 0.3048)
			(stroke
				(width 0.1)
				(type default)
			)
			(layer "F.Fab")
		)
		(fp_line
			(start -0.67945 -0.305054)
			(end -0.12065 -0.305054)
			(stroke
				(width 0.1)
				(type default)
			)
			(layer "F.Fab")
		)
		(fp_line
			(start -0.12065 -0.305054)
			(end -0.12065 -0.2794)
			(stroke
				(width 0.1)
				(type default)
			)
			(layer "F.Fab")
		)
		(pad "1" smd circle
			(at -0.40005 0 270)
			(size 0 0)
			(layers "F.Cu" "F.Mask" "F.Paste")
			(net "PCEPLL7_VDDA18_PEX0")
		)
		(pad "2" smd circle
			(at 0.40005 0 270)
			(size 0 0)
			(layers "F.Cu" "F.Mask" "F.Paste")
			(net "PCEPLL7_VDDA18_PEX0_R")
		)
	)
	(footprint ""
		(layer "F.Cu")
		(at 251.446792 -37.47516)
		(property "Reference" "R6087"
			(at 0 0 0)
			(layer "F.SilkS")
			(hide yes)
			(effects
				(font
					(size 1.27 1.27)
				)
			)
		)
		(property "Value" ""
			(at 0 0 0)
			(layer "F.Fab")
			(effects
				(font
					(size 1.27 1.27)
				)
			)
		)
		(duplicate_pad_numbers_are_jumpers no)
		(fp_line
			(start -0.7874 -0.4064)
			(end 0.7874 -0.4064)
			(stroke
				(width 0.1524)
				(type default)
			)
			(layer "F.SilkS")
		)
		(fp_line
			(start -0.7874 0.4064)
			(end -0.7874 -0.4064)
			(stroke
				(width 0.1524)
				(type default)
			)
			(layer "F.SilkS")
		)
		(fp_line
			(start 0.7874 -0.4064)
			(end 0.7874 0.4064)
			(stroke
				(width 0.1524)
				(type default)
			)
			(layer "F.SilkS")
		)
		(fp_line
			(start 0.7874 0.4064)
			(end -0.7874 0.4064)
			(stroke
				(width 0.1524)
				(type default)
			)
			(layer "F.SilkS")
		)
		(fp_line
			(start -0.67945 -0.305054)
			(end -0.12065 -0.305054)
			(stroke
				(width 0.1)
				(type default)
			)
			(layer "F.Fab")
		)
		(fp_line
			(start -0.67945 0.3048)
			(end -0.67945 -0.305054)
			(stroke
				(width 0.1)
				(type default)
			)
			(layer "F.Fab")
		)
		(fp_line
			(start -0.12065 -0.305054)
			(end -0.12065 -0.2794)
			(stroke
				(width 0.1)
				(type default)
			)
			(layer "F.Fab")
		)
		(fp_line
			(start -0.12065 -0.2794)
			(end 0.12065 -0.2794)
			(stroke
				(width 0.1)
				(type default)
			)
			(layer "F.Fab")
		)
		(fp_line
			(start -0.12065 0.2794)
			(end -0.12065 0.3048)
			(stroke
				(width 0.1)
				(type default)
			)
			(layer "F.Fab")
		)
		(fp_line
			(start -0.12065 0.3048)
			(end -0.67945 0.3048)
			(stroke
				(width 0.1)
				(type default)
			)
			(layer "F.Fab")
		)
		(fp_line
			(start 0.120396 0.2794)
			(end -0.12065 0.2794)
			(stroke
				(width 0.1)
				(type default)
			)
			(layer "F.Fab")
		)
		(fp_line
			(start 0.120396 0.3048)
			(end 0.120396 0.2794)
			(stroke
				(width 0.1)
				(type default)
			)
			(layer "F.Fab")
		)
		(fp_line
			(start 0.12065 -0.3048)
			(end 0.67945 -0.3048)
			(stroke
				(width 0.1)
				(type default)
			)
			(layer "F.Fab")
		)
		(fp_line
			(start 0.12065 -0.2794)
			(end 0.12065 -0.3048)
			(stroke
				(width 0.1)
				(type default)
			)
			(layer "F.Fab")
		)
		(fp_line
			(start 0.67945 -0.3048)
			(end 0.67945 0.3048)
			(stroke
				(width 0.1)
				(type default)
			)
			(layer "F.Fab")
		)
		(fp_line
			(start 0.67945 0.3048)
			(end 0.120396 0.3048)
			(stroke
				(width 0.1)
				(type default)
			)
			(layer "F.Fab")
		)
		(pad "1" smd circle
			(at -0.40005 0)
			(size 0 0)
			(layers "F.Cu" "F.Mask" "F.Paste")
			(net "P3V3_SSD9")
		)
		(pad "2" smd circle
			(at 0.40005 0)
			(size 0 0)
			(layers "F.Cu" "F.Mask" "F.Paste")
			(net "P3V3_SSD9_PG_G1")
		)
	)
	(footprint ""
		(layer "F.Cu")
		(at 268.402816 -92.526104 180)
		(property "Reference" "R1064"
			(at 0 0 180)
			(layer "F.SilkS")
			(hide yes)
			(effects
				(font
					(size 1.27 1.27)
				)
			)
		)
		(property "Value" ""
			(at 0 0 180)
			(layer "F.Fab")
			(effects
				(font
					(size 1.27 1.27)
				)
			)
		)
		(duplicate_pad_numbers_are_jumpers no)
		(fp_line
			(start 0.7874 0.4064)
			(end -0.7874 0.4064)
			(stroke
				(width 0.1524)
				(type default)
			)
			(layer "F.SilkS")
		)
		(fp_line
			(start 0.7874 -0.4064)
			(end 0.7874 0.4064)
			(stroke
				(width 0.1524)
				(type default)
			)
			(layer "F.SilkS")
		)
		(fp_line
			(start -0.7874 0.4064)
			(end -0.7874 -0.4064)
			(stroke
				(width 0.1524)
				(type default)
			)
			(layer "F.SilkS")
		)
		(fp_line
			(start -0.7874 -0.4064)
			(end 0.7874 -0.4064)
			(stroke
				(width 0.1524)
				(type default)
			)
			(layer "F.SilkS")
		)
		(fp_line
			(start 0.67945 0.3048)
			(end 0.120396 0.3048)
			(stroke
				(width 0.1)
				(type default)
			)
			(layer "F.Fab")
		)
		(fp_line
			(start 0.67945 -0.3048)
			(end 0.67945 0.3048)
			(stroke
				(width 0.1)
				(type default)
			)
			(layer "F.Fab")
		)
		(fp_line
			(start 0.12065 -0.2794)
			(end 0.12065 -0.3048)
			(stroke
				(width 0.1)
				(type default)
			)
			(layer "F.Fab")
		)
		(fp_line
			(start 0.12065 -0.3048)
			(end 0.67945 -0.3048)
			(stroke
				(width 0.1)
				(type default)
			)
			(layer "F.Fab")
		)
		(fp_line
			(start 0.120396 0.3048)
			(end 0.120396 0.2794)
			(stroke
				(width 0.1)
				(type default)
			)
			(layer "F.Fab")
		)
		(fp_line
			(start 0.120396 0.2794)
			(end -0.12065 0.2794)
			(stroke
				(width 0.1)
				(type default)
			)
			(layer "F.Fab")
		)
		(fp_line
			(start -0.12065 0.3048)
			(end -0.67945 0.3048)
			(stroke
				(width 0.1)
				(type default)
			)
			(layer "F.Fab")
		)
		(fp_line
			(start -0.12065 0.2794)
			(end -0.12065 0.3048)
			(stroke
				(width 0.1)
				(type default)
			)
			(layer "F.Fab")
		)
		(fp_line
			(start -0.12065 -0.2794)
			(end 0.12065 -0.2794)
			(stroke
				(width 0.1)
				(type default)
			)
			(layer "F.Fab")
		)
		(fp_line
			(start -0.12065 -0.305054)
			(end -0.12065 -0.2794)
			(stroke
				(width 0.1)
				(type default)
			)
			(layer "F.Fab")
		)
		(fp_line
			(start -0.67945 0.3048)
			(end -0.67945 -0.305054)
			(stroke
				(width 0.1)
				(type default)
			)
			(layer "F.Fab")
		)
		(fp_line
			(start -0.67945 -0.305054)
			(end -0.12065 -0.305054)
			(stroke
				(width 0.1)
				(type default)
			)
			(layer "F.Fab")
		)
		(pad "1" smd circle
			(at -0.40005 0 180)
			(size 0 0)
			(layers "F.Cu" "F.Mask" "F.Paste")
			(net "GND")
		)
		(pad "2" smd circle
			(at 0.40005 0 180)
			(size 0 0)
			(layers "F.Cu" "F.Mask" "F.Paste")
			(net "PU_CK440_SHFT_LD_N")
		)
	)
	(footprint ""
		(layer "F.Cu")
		(at 121.163588 -356.244906 90)
		(property "Reference" "C366"
			(at 0 0 90)
			(layer "F.SilkS")
			(hide yes)
			(effects
				(font
					(size 1.27 1.27)
				)
			)
		)
		(property "Value" ""
			(at 0 0 90)
			(layer "F.Fab")
			(effects
				(font
					(size 1.27 1.27)
				)
			)
		)
		(duplicate_pad_numbers_are_jumpers no)
		(fp_line
			(start 0.299974 -0.150114)
			(end 0.299974 0.150114)
			(stroke
				(width 0.1)
				(type default)
			)
			(layer "F.Fab")
		)
		(fp_line
			(start -0.299974 -0.150114)
			(end 0.299974 -0.150114)
			(stroke
				(width 0.1)
				(type default)
			)
			(layer "F.Fab")
		)
		(fp_line
			(start 0.299974 0.150114)
			(end -0.299974 0.150114)
			(stroke
				(width 0.1)
				(type default)
			)
			(layer "F.Fab")
		)
		(fp_line
			(start -0.299974 0.150114)
			(end -0.299974 -0.150114)
			(stroke
				(width 0.1)
				(type default)
			)
			(layer "F.Fab")
		)
		(pad "1" smd rect
			(at -0.2667 0 90)
			(size 0.3048 0.381)
			(layers "F.Cu" "F.Mask" "F.Paste")
			(net "P5E_PEX1_STN6_TX_DP<98>")
		)
		(pad "2" smd rect
			(at 0.2667 0 90)
			(size 0.3048 0.381)
			(layers "F.Cu" "F.Mask" "F.Paste")
			(net "P5E_PEX1_STN6_TX_C_DP<98>")
		)
	)
)
